(kicad_pcb
	(version 20260206)
	(generator "pcbnew")
	(generator_version "10.0")
	(general
		(thickness 1.6)
		(legacy_teardrops no)
	)
	(paper "A4")
	(title_block
		(title "Bryce Canyon_R.DPB_16317-1_OCP.brd")
		(comment 1 "Bryce Canyon / footprints 746-749 of 2099")
	)
	(layers
		(0 "F.Cu" signal "TOP")
		(4 "In1.Cu" signal "L2GND")
		(6 "In2.Cu" signal "L3")
		(8 "In3.Cu" signal "L4VCC")
		(10 "In4.Cu" signal "L5VCC")
		(12 "In5.Cu" signal "L6")
		(14 "In6.Cu" signal "L7GND")
		(2 "B.Cu" signal "BOTTOM")
		(9 "F.Adhes" user "F.Adhesive")
		(11 "B.Adhes" user "B.Adhesive")
		(13 "F.Paste" user "Package Geometry/Pastemask Top")
		(15 "B.Paste" user "Package Geometry/Pastemask Bottom")
		(5 "F.SilkS" user "Ref Des/Silkscreen Top")
		(7 "B.SilkS" user "Ref Des/Silkscreen Bottom")
		(1 "F.Mask" user "Board Geometry/Soldermask Top")
		(3 "B.Mask" user "Board Geometry/Soldermask Bottom")
		(17 "Dwgs.User" user "User.Drawings")
		(19 "Cmts.User" user "User.Comments")
		(21 "Eco1.User" user "User.Eco1")
		(23 "Eco2.User" user "User.Eco2")
		(25 "Edge.Cuts" user "Board Geometry/Outline")
		(27 "Margin" user)
		(31 "F.CrtYd" user "Package Geometry/Place Bound Top")
		(29 "B.CrtYd" user "Package Geometry/Place Bound Bottom")
		(35 "F.Fab" user "Ref Des/Assembly Top")
		(33 "B.Fab" user "Ref Des/Assembly Bottom")
	)
	(footprint ""
		(layer "F.Cu")
		(at 176.149 -131.572)
		(property "Reference" "R478"
			(at 0 0 0)
			(layer "F.SilkS")
			(hide yes)
			(effects
				(font
					(size 1.27 1.27)
				)
			)
		)
		(property "Value" "0R2J-2-GP"
			(at 0.064008 -3.993896 0)
			(unlocked yes)
			(layer "F.Fab")
			(hide yes)
			(effects
				(font
					(size 1.016 1.016)
					(thickness 0.1524)
				)
			)
		)
		(property "Device Type" "R402H16"
			(at 0.064008 -5.517896 0)
			(unlocked yes)
			(layer "F.Fab")
			(hide yes)
			(effects
				(font
					(size 1.016 1.016)
					(thickness 0.1524)
				)
			)
		)
		(duplicate_pad_numbers_are_jumpers no)
		(fp_line
			(start -0.508 -0.9398)
			(end -0.508 0.9398)
			(stroke
				(width 0.1524)
				(type default)
			)
			(layer "F.SilkS")
		)
		(fp_line
			(start 0.508 -0.9398)
			(end -0.508 -0.9398)
			(stroke
				(width 0.1524)
				(type default)
			)
			(layer "F.SilkS")
		)
		(fp_rect
			(start -0.508 0.9398)
			(end 0.508 -0.9398)
			(stroke
				(width 0)
				(type default)
			)
			(fill no)
			(layer "F.CrtYd")
		)
		(fp_rect
			(start -0.508 0.9398)
			(end 0.508 -0.9398)
			(stroke
				(width 0)
				(type default)
			)
			(fill no)
			(layer "F.Fab")
		)
		(pad "1" smd custom
			(at 0 -0.4445)
			(size 0.1397 0.1397)
			(layers "F.Cu" "F.Mask" "F.Paste")
			(net "SW_HDD_G17")
			(options
				(clearance outline)
				(anchor circle)
			)
			(primitives
				(gr_poly
					(pts
						(arc
							(start -0.1778 -0.2794)
							(mid -0.249642 -0.249642)
							(end -0.2794 -0.1778)
						)
						(arc
							(start -0.2794 0.1778)
							(mid -0.249642 0.249642)
							(end -0.1778 0.2794)
						)
						(arc
							(start 0.1778 0.2794)
							(mid 0.249642 0.249642)
							(end 0.2794 0.1778)
						)
						(arc
							(start 0.2794 -0.1778)
							(mid 0.249642 -0.249642)
							(end 0.1778 -0.2794)
						)
					)
					(width 0)
					(fill yes)
				)
			)
		)
		(pad "2" smd custom
			(at 0 0.4445)
			(size 0.1397 0.1397)
			(layers "F.Cu" "F.Mask" "F.Paste")
			(net "SW_HDD_R17")
			(options
				(clearance outline)
				(anchor circle)
			)
			(primitives
				(gr_poly
					(pts
						(arc
							(start -0.1778 -0.2794)
							(mid -0.249642 -0.249642)
							(end -0.2794 -0.1778)
						)
						(arc
							(start -0.2794 0.1778)
							(mid -0.249642 0.249642)
							(end -0.1778 0.2794)
						)
						(arc
							(start 0.1778 0.2794)
							(mid 0.249642 0.249642)
							(end 0.2794 0.1778)
						)
						(arc
							(start 0.2794 -0.1778)
							(mid 0.249642 -0.249642)
							(end 0.1778 -0.2794)
						)
					)
					(width 0)
					(fill yes)
				)
			)
		)
	)
	(footprint ""
		(layer "F.Cu")
		(at 83.566 -249.555 180)
		(property "Reference" "Q7"
			(at 0 0 180)
			(layer "F.SilkS")
			(hide yes)
			(effects
				(font
					(size 1.27 1.27)
				)
			)
		)
		(property "Value" "2N7002KDW-GP"
			(at -2.3622 -8.2042 180)
			(unlocked yes)
			(layer "F.Fab")
			(hide yes)
			(effects
				(font
					(size 1.016 1.016)
					(thickness 0.1524)
				)
			)
		)
		(property "Device Type" "SOT-363H44"
			(at -2.3622 -10.1092 180)
			(unlocked yes)
			(layer "F.Fab")
			(hide yes)
			(effects
				(font
					(size 1.016 1.016)
					(thickness 0.1524)
				)
			)
		)
		(duplicate_pad_numbers_are_jumpers no)
		(fp_line
			(start 1.4478 1.7018)
			(end 1.4478 -1.7018)
			(stroke
				(width 0.1524)
				(type default)
			)
			(layer "F.SilkS")
		)
		(fp_line
			(start 1.4478 -1.7018)
			(end -1.4478 -1.7018)
			(stroke
				(width 0.1524)
				(type default)
			)
			(layer "F.SilkS")
		)
		(fp_line
			(start -1.27 1.524)
			(end -1.27 0.6604)
			(stroke
				(width 0.4826)
				(type default)
			)
			(layer "F.SilkS")
		)
		(fp_line
			(start -1.4478 1.7018)
			(end 1.4478 1.7018)
			(stroke
				(width 0.1524)
				(type default)
			)
			(layer "F.SilkS")
		)
		(fp_line
			(start -1.4478 -1.7018)
			(end -1.4478 1.7018)
			(stroke
				(width 0.1524)
				(type default)
			)
			(layer "F.SilkS")
		)
		(fp_poly
			(pts
				(xy -1.524 -1.778) (xy 1.524 -1.778) (xy 1.524 1.778) (xy -1.524 1.778)
			)
			(stroke
				(width 0)
				(type default)
			)
			(fill no)
			(layer "F.CrtYd")
		)
		(fp_poly
			(pts
				(xy -1.524 -1.778) (xy 1.524 -1.778) (xy 1.524 1.778) (xy -1.524 1.778)
			)
			(stroke
				(width 0)
				(type default)
			)
			(fill no)
			(layer "F.Fab")
		)
		(pad "1" smd rect
			(at -0.65024 0.9398 180)
			(size 0.4064 1.016)
			(layers "F.Cu" "F.Mask" "F.Paste")
			(net "GND")
		)
		(pad "2" smd rect
			(at 0 0.9398 180)
			(size 0.4064 1.016)
			(layers "F.Cu" "F.Mask" "F.Paste")
			(net "SW_PWR_R_HDD2")
		)
		(pad "3" smd rect
			(at 0.65024 0.9398 180)
			(size 0.4064 1.016)
			(layers "F.Cu" "F.Mask" "F.Paste")
			(net "SW_HDD_P2")
		)
		(pad "4" smd rect
			(at 0.65024 -0.9398 180)
			(size 0.4064 1.016)
			(layers "F.Cu" "F.Mask" "F.Paste")
			(net "GND")
		)
		(pad "5" smd rect
			(at 0 -0.9398 180)
			(size 0.4064 1.016)
			(layers "F.Cu" "F.Mask" "F.Paste")
			(net "SW_HDD_G2")
		)
		(pad "6" smd rect
			(at -0.65024 -0.9398 180)
			(size 0.4064 1.016)
			(layers "F.Cu" "F.Mask" "F.Paste")
			(net "SW_HDD_R2")
		)
	)
	(footprint ""
		(layer "F.Cu")
		(at 331.7494 -249.4788 90)
		(property "Reference" "R259"
			(at 0 0 90)
			(layer "F.SilkS")
			(hide yes)
			(effects
				(font
					(size 1.27 1.27)
				)
			)
		)
		(property "Value" "4K7R2J-2-GP"
			(at 0.064008 -3.993896 90)
			(unlocked yes)
			(layer "F.Fab")
			(hide yes)
			(effects
				(font
					(size 1.016 1.016)
					(thickness 0.1524)
				)
			)
		)
		(property "Device Type" "R402H16"
			(at 0.064008 -5.517896 90)
			(unlocked yes)
			(layer "F.Fab")
			(hide yes)
			(effects
				(font
					(size 1.016 1.016)
					(thickness 0.1524)
				)
			)
		)
		(duplicate_pad_numbers_are_jumpers no)
		(fp_line
			(start 0.508 -0.9398)
			(end -0.508 -0.9398)
			(stroke
				(width 0.1524)
				(type default)
			)
			(layer "F.SilkS")
		)
		(fp_line
			(start -0.508 -0.9398)
			(end -0.508 0.9398)
			(stroke
				(width 0.1524)
				(type default)
			)
			(layer "F.SilkS")
		)
		(fp_rect
			(start -0.508 0.9398)
			(end 0.508 -0.9398)
			(stroke
				(width 0)
				(type default)
			)
			(fill no)
			(layer "F.CrtYd")
		)
		(fp_rect
			(start -0.508 0.9398)
			(end 0.508 -0.9398)
			(stroke
				(width 0)
				(type default)
			)
			(fill no)
			(layer "F.Fab")
		)
		(pad "1" smd custom
			(at 0 -0.4445 90)
			(size 0.1397 0.1397)
			(layers "F.Cu" "F.Mask" "F.Paste")
			(net "P12V_B")
			(options
				(clearance outline)
				(anchor circle)
			)
			(primitives
				(gr_poly
					(pts
						(arc
							(start -0.1778 -0.2794)
							(mid -0.249642 -0.249642)
							(end -0.2794 -0.1778)
						)
						(arc
							(start -0.2794 0.1778)
							(mid -0.249642 0.249642)
							(end -0.1778 0.2794)
						)
						(arc
							(start 0.1778 0.2794)
							(mid 0.249642 0.249642)
							(end 0.2794 0.1778)
						)
						(arc
							(start 0.2794 -0.1778)
							(mid 0.249642 -0.249642)
							(end 0.1778 -0.2794)
						)
					)
					(width 0)
					(fill yes)
				)
			)
		)
		(pad "2" smd custom
			(at 0 0.4445 90)
			(size 0.1397 0.1397)
			(layers "F.Cu" "F.Mask" "F.Paste")
			(net "SW_HDD_P6")
			(options
				(clearance outline)
				(anchor circle)
			)
			(primitives
				(gr_poly
					(pts
						(arc
							(start -0.1778 -0.2794)
							(mid -0.249642 -0.249642)
							(end -0.2794 -0.1778)
						)
						(arc
							(start -0.2794 0.1778)
							(mid -0.249642 0.249642)
							(end -0.1778 0.2794)
						)
						(arc
							(start 0.1778 0.2794)
							(mid 0.249642 0.249642)
							(end 0.2794 0.1778)
						)
						(arc
							(start 0.2794 -0.1778)
							(mid 0.249642 -0.249642)
							(end 0.1778 -0.2794)
						)
					)
					(width 0)
					(fill yes)
				)
			)
		)
	)
	(footprint ""
		(layer "F.Cu")
		(at 51.7652 -33.782 -90)
		(property "Reference" "C355"
			(at 0 0 270)
			(layer "F.SilkS")
			(hide yes)
			(effects
				(font
					(size 1.27 1.27)
				)
			)
		)
		(property "Value" "SC1U16V3KX-5GP"
			(at 0 -2.8194 270)
			(unlocked yes)
			(layer "F.Fab")
			(hide yes)
			(effects
				(font
					(size 1.016 1.016)
					(thickness 0.1524)
				)
			)
		)
		(property "Device Type" "C603H36"
			(at 0 -4.3434 270)
			(unlocked yes)
			(layer "F.Fab")
			(hide yes)
			(effects
				(font
					(size 1.016 1.016)
					(thickness 0.1524)
				)
			)
		)
		(duplicate_pad_numbers_are_jumpers no)
		(fp_line
			(start 0.508 0)
			(end -0.508 0)
			(stroke
				(width 0.2032)
				(type default)
			)
			(layer "F.SilkS")
		)
		(fp_rect
			(start -0.5842 1.3335)
			(end 0.5842 -1.3335)
			(stroke
				(width 0)
				(type default)
			)
			(fill no)
			(layer "F.CrtYd")
		)
		(fp_rect
			(start -0.5842 1.3335)
			(end 0.5842 -1.3335)
			(stroke
				(width 0)
				(type default)
			)
			(fill no)
			(layer "F.Fab")
		)
		(pad "1" smd custom
			(at 0 -0.762 270)
			(size 0.2159 0.2159)
			(layers "F.Cu" "F.Mask" "F.Paste")
			(net "P5V_HDD25")
			(options
				(clearance outline)
				(anchor circle)
			)
			(primitives
				(gr_poly
					(pts
						(arc
							(start -0.3302 -0.4318)
							(mid -0.402042 -0.402042)
							(end -0.4318 -0.3302)
						)
						(arc
							(start -0.4318 0.3302)
							(mid -0.402042 0.402042)
							(end -0.3302 0.4318)
						)
						(arc
							(start 0.3302 0.4318)
							(mid 0.402042 0.402042)
							(end 0.4318 0.3302)
						)
						(arc
							(start 0.4318 -0.3302)
							(mid 0.402042 -0.402042)
							(end 0.3302 -0.4318)
						)
					)
					(width 0)
					(fill yes)
				)
			)
		)
		(pad "2" smd custom
			(at 0 0.762 270)
			(size 0.2159 0.2159)
			(layers "F.Cu" "F.Mask" "F.Paste")
			(net "GND")
			(options
				(clearance outline)
				(anchor circle)
			)
			(primitives
				(gr_poly
					(pts
						(arc
							(start -0.3302 -0.4318)
							(mid -0.402042 -0.402042)
							(end -0.4318 -0.3302)
						)
						(arc
							(start -0.4318 0.3302)
							(mid -0.402042 0.402042)
							(end -0.3302 0.4318)
						)
						(arc
							(start 0.3302 0.4318)
							(mid 0.402042 0.402042)
							(end 0.4318 0.3302)
						)
						(arc
							(start 0.4318 -0.3302)
							(mid 0.402042 -0.402042)
							(end 0.3302 -0.4318)
						)
					)
					(width 0)
					(fill yes)
				)
			)
		)
	)
)
